(kicad_pcb
	(version 20240108)
	(generator "pcbnew")
	(generator_version "8.0")
	(general
		(thickness 1.586)
		(legacy_teardrops no)
	)
	(paper "A4")
	(title_block
		(title "GMSL Serializer")
		(date "2024-11-27")
		(rev "1.1.1")
		(company "Antmicro Ltd")
		(comment 1 "www.antmicro.com")
		(comment 9 "footprints 25-28 of 117")
	)
	(layers
		(0 "F.Cu" signal)
		(1 "In1.Cu" power)
		(2 "In2.Cu" power)
		(31 "B.Cu" signal)
		(32 "B.Adhes" user "B.Adhesive")
		(33 "F.Adhes" user "F.Adhesive")
		(34 "B.Paste" user)
		(35 "F.Paste" user)
		(36 "B.SilkS" user "B.Silkscreen")
		(37 "F.SilkS" user "F.Silkscreen")
		(38 "B.Mask" user)
		(39 "F.Mask" user)
		(40 "Dwgs.User" user "User.Drawings")
		(41 "Cmts.User" user "User.Comments")
		(42 "Eco1.User" user "User.Eco1")
		(43 "Eco2.User" user "User.Eco2")
		(44 "Edge.Cuts" user)
		(45 "Margin" user)
		(46 "B.CrtYd" user "B.Courtyard")
		(47 "F.CrtYd" user "F.Courtyard")
		(48 "B.Fab" user)
		(49 "F.Fab" user)
	)
	(footprint "antmicro-footprints:C_0402_1005Metric"
		(layer "F.Cu")
		(at 163.851 93.735)
		(descr "Capacitor SMD 0402")
		(tags "capacitor SMD 0402")
		(property "Reference" "C11"
			(at -1.006 1.32 0)
			(layer "F.SilkS")
			(effects
				(font
					(size 0.7 0.7)
					(thickness 0.15)
				)
				(justify left bottom)
			)
		)
		(property "Value" "C_10n_0402"
			(at -1.022927 2.155213 0)
			(layer "F.Fab")
			(effects
				(font
					(size 0.7 0.7)
					(thickness 0.15)
				)
				(justify left bottom)
			)
		)
		(property "Footprint" "antmicro-footprints:C_0402_1005Metric"
			(at 0 0 0)
			(layer "F.Fab")
			(hide yes)
			(effects
				(font
					(size 1.27 1.27)
					(thickness 0.15)
				)
			)
		)
		(property "Datasheet" "https://www.murata.com/products/productdetail?partno=GRM155R71H103KA88%23"
			(at 0 0 0)
			(layer "F.Fab")
			(hide yes)
			(effects
				(font
					(size 1.27 1.27)
					(thickness 0.15)
				)
			)
		)
		(property "Author" "Antmicro"
			(at 0 0 0)
			(layer "F.Fab")
			(hide yes)
			(effects
				(font
					(size 1 1)
					(thickness 0.15)
				)
			)
		)
		(property "Dielectric" "X7R"
			(at 0 0 0)
			(layer "F.Fab")
			(hide yes)
			(effects
				(font
					(size 1 1)
					(thickness 0.15)
				)
			)
		)
		(property "License" "Apache-2.0"
			(at 0 0 0)
			(layer "F.Fab")
			(hide yes)
			(effects
				(font
					(size 1 1)
					(thickness 0.15)
				)
			)
		)
		(property "MPN" "GRM155R71H103KA88D"
			(at 0 0 0)
			(layer "F.Fab")
			(hide yes)
			(effects
				(font
					(size 1 1)
					(thickness 0.15)
				)
			)
		)
		(property "Manufacturer" "Murata"
			(at 0 0 0)
			(layer "F.Fab")
			(hide yes)
			(effects
				(font
					(size 1 1)
					(thickness 0.15)
				)
			)
		)
		(property "Val" "10n"
			(at 0 0 0)
			(layer "F.Fab")
			(hide yes)
			(effects
				(font
					(size 1 1)
					(thickness 0.15)
				)
			)
		)
		(property "Voltage" "50V"
			(at 0 0 0)
			(layer "F.Fab")
			(hide yes)
			(effects
				(font
					(size 1 1)
					(thickness 0.15)
				)
			)
		)
		(sheetname "GMSL Connector")
		(sheetfile "GMSL.kicad_sch")
		(attr smd)
		(fp_rect
			(start -0.925 -0.47)
			(end 0.925 0.47)
			(stroke
				(width 0.05)
				(type default)
			)
			(fill none)
			(layer "F.CrtYd")
		)
		(fp_line
			(start -0.494 -0.25)
			(end 0.504 -0.25)
			(stroke
				(width 0.15)
				(type solid)
			)
			(layer "F.Fab")
		)
		(fp_line
			(start -0.494 0.248)
			(end -0.494 -0.25)
			(stroke
				(width 0.15)
				(type solid)
			)
			(layer "F.Fab")
		)
		(fp_line
			(start 0.504 -0.25)
			(end 0.504 0.248)
			(stroke
				(width 0.15)
				(type solid)
			)
			(layer "F.Fab")
		)
		(fp_line
			(start 0.504 0.248)
			(end -0.494 0.248)
			(stroke
				(width 0.15)
				(type solid)
			)
			(layer "F.Fab")
		)
		(fp_text user "License: Apache-2.0"
			(at -0.939 5.799 0)
			(layer "F.Fab")
			(hide yes)
			(effects
				(font
					(size 0.7 0.7)
					(thickness 0.15)
				)
				(justify left bottom)
			)
		)
		(fp_text user "${REFERENCE}"
			(at -0.939 4.599 0)
			(layer "F.Fab")
			(hide yes)
			(effects
				(font
					(size 0.7 0.7)
					(thickness 0.15)
				)
				(justify left bottom)
			)
		)
		(fp_text user "Author: Antmicro"
			(at -0.939 3.399 0)
			(layer "F.Fab")
			(hide yes)
			(effects
				(font
					(size 0.7 0.7)
					(thickness 0.15)
				)
				(justify left bottom)
			)
		)
		(pad "1" smd roundrect
			(at -0.48 0)
			(size 0.59 0.64)
			(layers "F.Cu" "F.Paste" "F.Mask")
			(roundrect_rratio 0.25)
			(net 1 "GND")
			(pintype "passive")
		)
		(pad "2" smd roundrect
			(at 0.48 0)
			(size 0.59 0.64)
			(layers "F.Cu" "F.Paste" "F.Mask")
			(roundrect_rratio 0.25)
			(net 2 "+12V")
			(pintype "passive")
		)
	)
	(footprint "antmicro-footprints:R_0402_1005Metric"
		(layer "F.Cu")
		(at 150.15 110.28 180)
		(descr "Resistor SMD 0402")
		(tags "resistor SMD 0402")
		(property "Reference" "R19"
			(at -3.03 -0.4 0)
			(layer "F.SilkS")
			(effects
				(font
					(size 0.7 0.7)
					(thickness 0.15)
				)
				(justify right bottom)
			)
		)
		(property "Value" "R_10k_0402"
			(at -1.011843 1.772047 0)
			(layer "F.Fab")
			(effects
				(font
					(size 0.7 0.7)
					(thickness 0.15)
				)
				(justify right bottom)
			)
		)
		(property "Footprint" "antmicro-footprints:R_0402_1005Metric"
			(at 0 0 180)
			(layer "F.Fab")
			(hide yes)
			(effects
				(font
					(size 1.27 1.27)
					(thickness 0.15)
				)
			)
		)
		(property "Datasheet" "https://www.bourns.com/docs/product-datasheets/cr.pdf"
			(at 0 0 180)
			(layer "F.Fab")
			(hide yes)
			(effects
				(font
					(size 1.27 1.27)
					(thickness 0.15)
				)
			)
		)
		(property "Author" "Antmicro"
			(at 300.3 220.56 0)
			(layer "F.Fab")
			(hide yes)
			(effects
				(font
					(size 1 1)
					(thickness 0.15)
				)
			)
		)
		(property "License" "Apache-2.0"
			(at 300.3 220.56 0)
			(layer "F.Fab")
			(hide yes)
			(effects
				(font
					(size 1 1)
					(thickness 0.15)
				)
			)
		)
		(property "MPN" "CR0402-FX-1002GLF"
			(at 300.3 220.56 0)
			(layer "F.Fab")
			(hide yes)
			(effects
				(font
					(size 1 1)
					(thickness 0.15)
				)
			)
		)
		(property "Manufacturer" "Bourns"
			(at 300.3 220.56 0)
			(layer "F.Fab")
			(hide yes)
			(effects
				(font
					(size 1 1)
					(thickness 0.15)
				)
			)
		)
		(property "Tolerance" "1%"
			(at 300.3 220.56 0)
			(layer "F.Fab")
			(hide yes)
			(effects
				(font
					(size 1 1)
					(thickness 0.15)
				)
			)
		)
		(property "Val" "10k"
			(at 300.3 220.56 0)
			(layer "F.Fab")
			(hide yes)
			(effects
				(font
					(size 1 1)
					(thickness 0.15)
				)
			)
		)
		(sheetname "Serializer")
		(sheetfile "serializer.kicad_sch")
		(attr smd)
		(fp_rect
			(start -0.925 -0.47)
			(end 0.925 0.47)
			(stroke
				(width 0.05)
				(type default)
			)
			(fill none)
			(layer "F.CrtYd")
		)
		(fp_rect
			(start -0.5 -0.25)
			(end 0.5 0.25)
			(stroke
				(width 0.15)
				(type solid)
			)
			(fill none)
			(layer "F.Fab")
		)
		(fp_text user "License: Apache-2.0"
			(at -0.95 5.169 0)
			(layer "F.Fab")
			(hide yes)
			(effects
				(font
					(size 0.7 0.7)
					(thickness 0.15)
				)
				(justify right bottom)
			)
		)
		(fp_text user "Author: Antmicro"
			(at -0.95 4.169 0)
			(layer "F.Fab")
			(hide yes)
			(effects
				(font
					(size 0.7 0.7)
					(thickness 0.15)
				)
				(justify right bottom)
			)
		)
		(fp_text user "${REFERENCE}"
			(at -0.95 3.168 0)
			(layer "F.Fab")
			(hide yes)
			(effects
				(font
					(size 0.7 0.7)
					(thickness 0.15)
				)
				(justify right bottom)
			)
		)
		(pad "1" smd roundrect
			(at -0.48 0 180)
			(size 0.59 0.64)
			(layers "F.Cu" "F.Paste" "F.Mask")
			(roundrect_rratio 0.25)
			(net 1 "GND")
			(pintype "passive")
		)
		(pad "2" smd roundrect
			(at 0.48 0 180)
			(size 0.59 0.64)
			(layers "F.Cu" "F.Paste" "F.Mask")
			(roundrect_rratio 0.25)
			(net 66 "/Serializer/CFG0")
			(pintype "passive")
		)
	)
	(footprint "antmicro-footprints:R_0402_1005Metric"
		(layer "F.Cu")
		(at 148.15 109.205 180)
		(descr "Resistor SMD 0402")
		(tags "resistor SMD 0402")
		(property "Reference" "R28"
			(at 0.88 -0.47 0)
			(layer "F.SilkS")
			(effects
				(font
					(size 0.7 0.7)
					(thickness 0.15)
				)
				(justify right bottom)
			)
		)
		(property "Value" "R_10k_0402"
			(at -1.011843 1.772047 0)
			(layer "F.Fab")
			(effects
				(font
					(size 0.7 0.7)
					(thickness 0.15)
				)
				(justify right bottom)
			)
		)
		(property "Footprint" "antmicro-footprints:R_0402_1005Metric"
			(at 0 0 180)
			(layer "F.Fab")
			(hide yes)
			(effects
				(font
					(size 1.27 1.27)
					(thickness 0.15)
				)
			)
		)
		(property "Datasheet" "https://www.bourns.com/docs/product-datasheets/cr.pdf"
			(at 0 0 180)
			(layer "F.Fab")
			(hide yes)
			(effects
				(font
					(size 1.27 1.27)
					(thickness 0.15)
				)
			)
		)
		(property "Author" "Antmicro"
			(at 296.3 218.41 0)
			(layer "F.Fab")
			(hide yes)
			(effects
				(font
					(size 1 1)
					(thickness 0.15)
				)
			)
		)
		(property "License" "Apache-2.0"
			(at 296.3 218.41 0)
			(layer "F.Fab")
			(hide yes)
			(effects
				(font
					(size 1 1)
					(thickness 0.15)
				)
			)
		)
		(property "MPN" "CR0402-FX-1002GLF"
			(at 296.3 218.41 0)
			(layer "F.Fab")
			(hide yes)
			(effects
				(font
					(size 1 1)
					(thickness 0.15)
				)
			)
		)
		(property "Manufacturer" "Bourns"
			(at 296.3 218.41 0)
			(layer "F.Fab")
			(hide yes)
			(effects
				(font
					(size 1 1)
					(thickness 0.15)
				)
			)
		)
		(property "Tolerance" "1%"
			(at 296.3 218.41 0)
			(layer "F.Fab")
			(hide yes)
			(effects
				(font
					(size 1 1)
					(thickness 0.15)
				)
			)
		)
		(property "Val" "10k"
			(at 296.3 218.41 0)
			(layer "F.Fab")
			(hide yes)
			(effects
				(font
					(size 1 1)
					(thickness 0.15)
				)
			)
		)
		(sheetname "Serializer")
		(sheetfile "serializer.kicad_sch")
		(attr smd)
		(fp_rect
			(start -0.925 -0.47)
			(end 0.925 0.47)
			(stroke
				(width 0.05)
				(type default)
			)
			(fill none)
			(layer "F.CrtYd")
		)
		(fp_rect
			(start -0.5 -0.25)
			(end 0.5 0.25)
			(stroke
				(width 0.15)
				(type solid)
			)
			(fill none)
			(layer "F.Fab")
		)
		(fp_text user "${REFERENCE}"
			(at -0.95 3.168 0)
			(layer "F.Fab")
			(hide yes)
			(effects
				(font
					(size 0.7 0.7)
					(thickness 0.15)
				)
				(justify right bottom)
			)
		)
		(fp_text user "License: Apache-2.0"
			(at -0.95 5.169 0)
			(layer "F.Fab")
			(hide yes)
			(effects
				(font
					(size 0.7 0.7)
					(thickness 0.15)
				)
				(justify right bottom)
			)
		)
		(fp_text user "Author: Antmicro"
			(at -0.95 4.169 0)
			(layer "F.Fab")
			(hide yes)
			(effects
				(font
					(size 0.7 0.7)
					(thickness 0.15)
				)
				(justify right bottom)
			)
		)
		(pad "1" smd roundrect
			(at -0.48 0 180)
			(size 0.59 0.64)
			(layers "F.Cu" "F.Paste" "F.Mask")
			(roundrect_rratio 0.25)
			(net 77 "Net-(U6-PWDNB)")
			(pintype "passive")
		)
		(pad "2" smd roundrect
			(at 0.48 0 180)
			(size 0.59 0.64)
			(layers "F.Cu" "F.Paste" "F.Mask")
			(roundrect_rratio 0.25)
			(net 10 "+3V3")
			(pintype "passive")
		)
	)
	(footprint "antmicro-footprints:SOT-23-3"
		(layer "F.Cu")
		(at 152.33 107.14 180)
		(property "Reference" "U4"
			(at -0.833 1.754 0)
			(layer "F.SilkS")
			(effects
				(font
					(size 0.7 0.7)
					(thickness 0.15)
				)
				(justify right bottom)
			)
		)
		(property "Value" "REF3012AIDBZT"
			(at -1.9 2.7 0)
			(layer "F.Fab")
			(effects
				(font
					(size 0.7 0.7)
					(thickness 0.15)
				)
				(justify right bottom)
			)
		)
		(property "Footprint" "antmicro-footprints:SOT-23-3"
			(at 0 0 180)
			(layer "F.Fab")
			(hide yes)
			(effects
				(font
					(size 1.27 1.27)
					(thickness 0.15)
				)
			)
		)
		(property "Datasheet" "https://www.ti.com/lit/gpn/REF3012"
			(at 0 0 180)
			(layer "F.Fab")
			(hide yes)
			(effects
				(font
					(size 1.27 1.27)
					(thickness 0.15)
				)
			)
		)
		(property "Author" "Antmicro"
			(at 304.66 214.28 0)
			(layer "F.Fab")
			(hide yes)
			(effects
				(font
					(size 1 1)
					(thickness 0.15)
				)
			)
		)
		(property "License" "Apache-2.0"
			(at 304.66 214.28 0)
			(layer "F.Fab")
			(hide yes)
			(effects
				(font
					(size 1 1)
					(thickness 0.15)
				)
			)
		)
		(property "MPN" "REF3012AIDBZT"
			(at 304.66 214.28 0)
			(layer "F.Fab")
			(hide yes)
			(effects
				(font
					(size 1 1)
					(thickness 0.15)
				)
			)
		)
		(property "Manufacturer" "Texas Instruments"
			(at 304.66 214.28 0)
			(layer "F.Fab")
			(hide yes)
			(effects
				(font
					(size 1 1)
					(thickness 0.15)
				)
			)
		)
		(sheetname "Supply")
		(sheetfile "supply.kicad_sch")
		(attr smd dnp)
		(fp_line
			(start 0.7 1.5)
			(end -0.7 1.5)
			(stroke
				(width 0.15)
				(type solid)
			)
			(layer "F.SilkS")
		)
		(fp_line
			(start 0.7 0.4)
			(end 0.7 1.5)
			(stroke
				(width 0.15)
				(type solid)
			)
			(layer "F.SilkS")
		)
		(fp_line
			(start 0.7 -0.4)
			(end 0.7 -1.5)
			(stroke
				(width 0.15)
				(type solid)
			)
			(layer "F.SilkS")
		)
		(fp_line
			(start 0.7 -1.5)
			(end -0.7 -1.5)
			(stroke
				(width 0.15)
				(type solid)
			)
			(layer "F.SilkS")
		)
		(fp_line
			(start -0.7 1.5)
			(end -0.7 1.35)
			(stroke
				(width 0.15)
				(type solid)
			)
			(layer "F.SilkS")
		)
		(fp_line
			(start -0.85 -1.35)
			(end -0.7 -1.5)
			(stroke
				(width 0.15)
				(type solid)
			)
			(layer "F.SilkS")
		)
		(fp_line
			(start -1.45 -1.35)
			(end -0.85 -1.35)
			(stroke
				(width 0.15)
				(type solid)
			)
			(layer "F.SilkS")
		)
		(fp_line
			(start 1.75 0.45)
			(end 0.85 0.45)
			(stroke
				(width 0.05)
				(type solid)
			)
			(layer "F.CrtYd")
		)
		(fp_line
			(start 1.75 -0.45)
			(end 1.75 0.45)
			(stroke
				(width 0.05)
				(type solid)
			)
			(layer "F.CrtYd")
		)
		(fp_line
			(start 0.85 1.65)
			(end -0.85 1.65)
			(stroke
				(width 0.05)
				(type solid)
			)
			(layer "F.CrtYd")
		)
		(fp_line
			(start 0.85 0.45)
			(end 0.85 1.65)
			(stroke
				(width 0.05)
				(type solid)
			)
			(layer "F.CrtYd")
		)
		(fp_line
			(start 0.825 -0.45)
			(end 1.75 -0.45)
			(stroke
				(width 0.05)
				(type solid)
			)
			(layer "F.CrtYd")
		)
		(fp_line
			(start 0.825 -1.6)
			(end 0.825 -0.45)
			(stroke
				(width 0.05)
				(type solid)
			)
			(layer "F.CrtYd")
		)
		(fp_line
			(start -0.85 1.65)
			(end -0.85 1.4)
			(stroke
				(width 0.05)
				(type solid)
			)
			(layer "F.CrtYd")
		)
		(fp_line
			(start -0.85 1.4)
			(end -1.75 1.4)
			(stroke
				(width 0.05)
				(type solid)
			)
			(layer "F.CrtYd")
		)
		(fp_line
			(start -0.85 0.5)
			(end -0.85 -0.5)
			(stroke
				(width 0.05)
				(type solid)
			)
			(layer "F.CrtYd")
		)
		(fp_line
			(start -0.85 -0.5)
			(end -1.75 -0.5)
			(stroke
				(width 0.05)
				(type solid)
			)
			(layer "F.CrtYd")
		)
		(fp_line
			(start -0.9 -1.4)
			(end -1.75 -1.4)
			(stroke
				(width 0.05)
				(type solid)
			)
			(layer "F.CrtYd")
		)
		(fp_line
			(start -0.9 -1.6)
			(end 0.825 -1.6)
			(stroke
				(width 0.05)
				(type solid)
			)
			(layer "F.CrtYd")
		)
		(fp_line
			(start -0.9 -1.6)
			(end -0.9 -1.4)
			(stroke
				(width 0.05)
				(type solid)
			)
			(layer "F.CrtYd")
		)
		(fp_line
			(start -1.75 1.4)
			(end -1.75 0.5)
			(stroke
				(width 0.05)
				(type solid)
			)
			(layer "F.CrtYd")
		)
		(fp_line
			(start -1.75 0.5)
			(end -0.85 0.5)
			(stroke
				(width 0.05)
				(type solid)
			)
			(layer "F.CrtYd")
		)
		(fp_line
			(start -1.75 -0.5)
			(end -1.75 -1.4)
			(stroke
				(width 0.05)
				(type solid)
			)
			(layer "F.CrtYd")
		)
		(fp_line
			(start 0.688 1.519)
			(end 0.688 -1.52)
			(stroke
				(width 0.15)
				(type solid)
			)
			(layer "F.Fab")
		)
		(fp_line
			(start -0.437 -1.526)
			(end 0.688 -1.526)
			(stroke
				(width 0.15)
				(type solid)
			)
			(layer "F.Fab")
		)
		(fp_line
			(start -0.437 -1.526)
			(end -0.712 -1.325)
			(stroke
				(width 0.15)
				(type solid)
			)
			(layer "F.Fab")
		)
		(fp_line
			(start -0.712 1.519)
			(end 0.688 1.519)
			(stroke
				(width 0.15)
				(type solid)
			)
			(layer "F.Fab")
		)
		(fp_line
			(start -0.712 -1.325)
			(end -0.712 1.523)
			(stroke
				(width 0.15)
				(type solid)
			)
			(layer "F.Fab")
		)
		(fp_text user "${REFERENCE}"
			(at -1.837 4 0)
			(layer "F.Fab")
			(hide yes)
			(effects
				(font
					(size 0.7 0.7)
					(thickness 0.15)
				)
				(justify right bottom)
			)
		)
		(fp_text user "License: Apache-2.0"
			(at -1.8 6.8 0)
			(layer "F.Fab")
			(hide yes)
			(effects
				(font
					(size 0.7 0.7)
					(thickness 0.15)
				)
				(justify right bottom)
			)
		)
		(fp_text user "Author: Antmicro"
			(at -1.837 5.3 0)
			(layer "F.Fab")
			(hide yes)
			(effects
				(font
					(size 0.7 0.7)
					(thickness 0.15)
				)
				(justify right bottom)
			)
		)
		(pad "1" smd roundrect
			(at -1.1 -0.951 180)
			(size 1 0.6)
			(layers "F.Cu" "F.Paste" "F.Mask")
			(roundrect_rratio 0.15)
			(net 9 "+5V")
			(pinfunction "IN")
			(pintype "power_in")
		)
		(pad "2" smd roundrect
			(at -1.1 0.949 180)
			(size 1 0.6)
			(layers "F.Cu" "F.Paste" "F.Mask")
			(roundrect_rratio 0.15)
			(net 90 "/Serializer/VREF")
			(pinfunction "OUT")
			(pintype "output")
		)
		(pad "3" smd roundrect
			(at 1.1 -0.0005 180)
			(size 1 0.6)
			(layers "F.Cu" "F.Paste" "F.Mask")
			(roundrect_rratio 0.15)
			(net 1 "GND")
			(pinfunction "GND")
			(pintype "passive")
		)
	)
)
